# T6G (Grand Teton) — schematic netlist excerpt (pin names and nets, part order shuffled) for the footprints in the layout excerpt that follows; sources: Cadence DE-HDL packaged netlist, KiCad conversion of 04192023_DAF0TMB3IC0_F0TG_MB_C_brd_V02_OCP.brd

C187  Q_CAP  1UF 4V 20% X6S  pkg 0201  page 323 : A = P0V9_CPU1_RT0_2A_2D ; B = GND
PC502_1  Q_CAP  22UF 4V 20% X6S  pkg C0805  page 194 : A = PVDDCR_CPU0_P0 ; B = GND
R8014  Q_RES  0 5% EMPTY  pkg 0402LF  page 143 : A = OCP_SFF_PRSNT23_R_N ; B = OCP_SFF_PRSNT23_R1_N

(kicad_pcb
	(version 20260206)
	(generator "pcbnew")
	(generator_version "10.0")
	(general
		(thickness 1.6)
		(legacy_teardrops no)
	)
	(paper "A4")
	(title_block
		(title "04192023_DAF0TMB3IC0_F0TG_MB_C_brd_V02_OCP.brd")
		(comment 1 "Grand Teton / footprints 7596-7598 of 8354")
	)
	(layers
		(0 "F.Cu" signal "TOP")
		(4 "In1.Cu" signal "GND")
		(6 "In2.Cu" signal "IN1")
		(8 "In3.Cu" signal "GND1")
		(10 "In4.Cu" signal "IN2")
		(12 "In5.Cu" signal "GND2")
		(14 "In6.Cu" signal "IN3")
		(16 "In7.Cu" signal "GND3")
		(18 "In8.Cu" signal "VCC")
		(20 "In9.Cu" signal "VCC1")
		(22 "In10.Cu" signal "GND4")
		(24 "In11.Cu" signal "IN4")
		(26 "In12.Cu" signal "GND5")
		(28 "In13.Cu" signal "IN5")
		(30 "In14.Cu" signal "GND6")
		(32 "In15.Cu" signal "IN6")
		(34 "In16.Cu" signal "GND7")
		(2 "B.Cu" signal "BOTTOM")
		(9 "F.Adhes" user "F.Adhesive")
		(11 "B.Adhes" user "B.Adhesive")
		(13 "F.Paste" user "Package Geometry/Pastemask Top")
		(15 "B.Paste" user "Package Geometry/Pastemask Bottom")
		(5 "F.SilkS" user "Ref Des/Silkscreen Top")
		(7 "B.SilkS" user "Ref Des/Silkscreen Bottom")
		(1 "F.Mask" user "Board Geometry/Soldermask Top")
		(3 "B.Mask" user "Board Geometry/Soldermask Bottom")
		(17 "Dwgs.User" user "User.Drawings")
		(19 "Cmts.User" user "User.Comments")
		(21 "Eco1.User" user "User.Eco1")
		(23 "Eco2.User" user "User.Eco2")
		(25 "Edge.Cuts" user "Board Geometry/Outline")
		(27 "Margin" user)
		(31 "F.CrtYd" user "Package Geometry/Place Bound Top")
		(29 "B.CrtYd" user "Package Geometry/Place Bound Bottom")
		(35 "F.Fab" user "Ref Des/Assembly Top")
		(33 "B.Fab" user "Ref Des/Assembly Bottom")
	)
	(footprint ""
		(layer "B.Cu")
		(at 8.382 -81.153 90)
		(property "Reference" "R8014"
			(at 0 0 90)
			(layer "B.SilkS")
			(hide yes)
			(effects
				(font
					(size 1.27 1.27)
				)
				(justify mirror)
			)
		)
		(property "Value" ""
			(at 0 0 90)
			(layer "B.Fab")
			(effects
				(font
					(size 1.27 1.27)
				)
				(justify mirror)
			)
		)
		(duplicate_pad_numbers_are_jumpers no)
		(fp_line
			(start 0.7874 -0.4064)
			(end -0.7874 -0.4064)
			(stroke
				(width 0.1524)
				(type default)
			)
			(layer "B.SilkS")
		)
		(fp_line
			(start -0.7874 -0.4064)
			(end -0.7874 0.4064)
			(stroke
				(width 0.1524)
				(type default)
			)
			(layer "B.SilkS")
		)
		(fp_line
			(start 0.7874 0.4064)
			(end 0.7874 -0.4064)
			(stroke
				(width 0.1524)
				(type default)
			)
			(layer "B.SilkS")
		)
		(fp_line
			(start -0.7874 0.4064)
			(end 0.7874 0.4064)
			(stroke
				(width 0.1524)
				(type default)
			)
			(layer "B.SilkS")
		)
		(fp_line
			(start 0.67945 -0.305054)
			(end 0.12065 -0.305054)
			(stroke
				(width 0.1)
				(type default)
			)
			(layer "B.Fab")
		)
		(fp_line
			(start 0.12065 -0.305054)
			(end 0.12065 -0.2794)
			(stroke
				(width 0.1)
				(type default)
			)
			(layer "B.Fab")
		)
		(fp_line
			(start -0.12065 -0.3048)
			(end -0.67945 -0.3048)
			(stroke
				(width 0.1)
				(type default)
			)
			(layer "B.Fab")
		)
		(fp_line
			(start -0.67945 -0.3048)
			(end -0.67945 0.3048)
			(stroke
				(width 0.1)
				(type default)
			)
			(layer "B.Fab")
		)
		(fp_line
			(start 0.12065 -0.2794)
			(end -0.12065 -0.2794)
			(stroke
				(width 0.1)
				(type default)
			)
			(layer "B.Fab")
		)
		(fp_line
			(start -0.12065 -0.2794)
			(end -0.12065 -0.3048)
			(stroke
				(width 0.1)
				(type default)
			)
			(layer "B.Fab")
		)
		(fp_line
			(start 0.12065 0.2794)
			(end 0.12065 0.3048)
			(stroke
				(width 0.1)
				(type default)
			)
			(layer "B.Fab")
		)
		(fp_line
			(start -0.120396 0.2794)
			(end 0.12065 0.2794)
			(stroke
				(width 0.1)
				(type default)
			)
			(layer "B.Fab")
		)
		(fp_line
			(start 0.67945 0.3048)
			(end 0.67945 -0.305054)
			(stroke
				(width 0.1)
				(type default)
			)
			(layer "B.Fab")
		)
		(fp_line
			(start 0.12065 0.3048)
			(end 0.67945 0.3048)
			(stroke
				(width 0.1)
				(type default)
			)
			(layer "B.Fab")
		)
		(fp_line
			(start -0.120396 0.3048)
			(end -0.120396 0.2794)
			(stroke
				(width 0.1)
				(type default)
			)
			(layer "B.Fab")
		)
		(fp_line
			(start -0.67945 0.3048)
			(end -0.120396 0.3048)
			(stroke
				(width 0.1)
				(type default)
			)
			(layer "B.Fab")
		)
		(pad "1" smd circle
			(at 0.40005 0 270)
			(size 0 0)
			(layers "B.Cu" "B.Mask" "B.Paste")
			(net "OCP_SFF_PRSNT23_R_N")
		)
		(pad "2" smd circle
			(at -0.40005 0 270)
			(size 0 0)
			(layers "B.Cu" "B.Mask" "B.Paste")
			(net "OCP_SFF_PRSNT23_R1_N")
		)
	)
	(footprint ""
		(layer "B.Cu")
		(at 60.578492 -386.766562 90)
		(property "Reference" "C187"
			(at 0 0 90)
			(layer "B.SilkS")
			(hide yes)
			(effects
				(font
					(size 1.27 1.27)
				)
				(justify mirror)
			)
		)
		(property "Value" ""
			(at 0 0 90)
			(layer "B.Fab")
			(effects
				(font
					(size 1.27 1.27)
				)
				(justify mirror)
			)
		)
		(duplicate_pad_numbers_are_jumpers no)
		(fp_line
			(start 0.299974 -0.150114)
			(end -0.299974 -0.150114)
			(stroke
				(width 0.1)
				(type default)
			)
			(layer "B.Fab")
		)
		(fp_line
			(start -0.299974 -0.150114)
			(end -0.299974 0.150114)
			(stroke
				(width 0.1)
				(type default)
			)
			(layer "B.Fab")
		)
		(fp_line
			(start 0.299974 0.150114)
			(end 0.299974 -0.150114)
			(stroke
				(width 0.1)
				(type default)
			)
			(layer "B.Fab")
		)
		(fp_line
			(start -0.299974 0.150114)
			(end 0.299974 0.150114)
			(stroke
				(width 0.1)
				(type default)
			)
			(layer "B.Fab")
		)
		(pad "1" smd rect
			(at 0.2667 0 270)
			(size 0.3048 0.381)
			(layers "B.Cu" "B.Mask" "B.Paste")
			(net "P0V9_CPU1_RT0_2A_2D")
		)
		(pad "2" smd rect
			(at -0.2667 0 270)
			(size 0.3048 0.381)
			(layers "B.Cu" "B.Mask" "B.Paste")
			(net "GND")
		)
	)
	(footprint ""
		(layer "B.Cu")
		(at 350.429576 -171.35094 90)
		(property "Reference" "PC502_1"
			(at 0 0 90)
			(layer "B.SilkS")
			(hide yes)
			(effects
				(font
					(size 1.27 1.27)
				)
				(justify mirror)
			)
		)
		(property "Value" ""
			(at 0 0 90)
			(layer "B.Fab")
			(effects
				(font
					(size 1.27 1.27)
				)
				(justify mirror)
			)
		)
		(duplicate_pad_numbers_are_jumpers no)
		(fp_line
			(start 1.524 -0.762)
			(end -1.524 -0.762)
			(stroke
				(width 0.1524)
				(type default)
			)
			(layer "B.SilkS")
		)
		(fp_line
			(start -1.524 -0.762)
			(end -1.524 0.762)
			(stroke
				(width 0.1524)
				(type default)
			)
			(layer "B.SilkS")
		)
		(fp_line
			(start 1.524 0.762)
			(end 1.524 -0.762)
			(stroke
				(width 0.1524)
				(type default)
			)
			(layer "B.SilkS")
		)
		(fp_line
			(start -1.524 0.762)
			(end 1.524 0.762)
			(stroke
				(width 0.1524)
				(type default)
			)
			(layer "B.SilkS")
		)
		(fp_line
			(start 1.1049 -0.724916)
			(end 1.1049 0.724916)
			(stroke
				(width 0.1)
				(type default)
			)
			(layer "B.Fab")
		)
		(fp_line
			(start -1.1049 -0.724916)
			(end 1.1049 -0.724916)
			(stroke
				(width 0.1)
				(type default)
			)
			(layer "B.Fab")
		)
		(fp_line
			(start 1.1049 0.724916)
			(end -1.1049 0.724916)
			(stroke
				(width 0.1)
				(type default)
			)
			(layer "B.Fab")
		)
		(fp_line
			(start -1.1049 0.724916)
			(end -1.1049 -0.724916)
			(stroke
				(width 0.1)
				(type default)
			)
			(layer "B.Fab")
		)
		(pad "1" smd rect
			(at 0.889 0 90)
			(size 1.016 1.27)
			(layers "B.Cu" "B.Mask" "B.Paste")
			(net "PVDDCR_CPU0_P0")
		)
		(pad "2" smd rect
			(at -0.889 0 90)
			(size 1.016 1.27)
			(layers "B.Cu" "B.Mask" "B.Paste")
			(net "GND")
		)
	)
)
